# BASEBOARD_FAB2 (Tioga Pass) — schematic netlist excerpt (pin names and nets, part order shuffled) for the footprints in the layout excerpt that follows; sources: Cadence DE-HDL packaged netlist, KiCad conversion of Wiwynn_Tioga_Pass_MB.brd

R9A21  RES  4.75K 1% CHIP  pkg 0402  page 119 : A = P3V3_STBY ; B = FM_PWR_LED_N
R7W18  RES  0.0 5% CHIP  pkg 0402  page 120 : A = IRQ_SML1_PMBUS_ALERT_N ; B = IRQ_SML1_PMBUS_ALERT_R1_N

(kicad_pcb
	(version 20260206)
	(generator "pcbnew")
	(generator_version "10.0")
	(general
		(thickness 1.6)
		(legacy_teardrops no)
	)
	(paper "A4")
	(title_block
		(title "Wiwynn_Tioga_Pass_MB.brd")
		(comment 1 "Tioga Pass / footprints 793-794 of 4770")
	)
	(layers
		(0 "F.Cu" signal "TOP")
		(4 "In1.Cu" signal "L2GND")
		(6 "In2.Cu" signal "L3")
		(8 "In3.Cu" signal "L4GND")
		(10 "In4.Cu" signal "L5")
		(12 "In5.Cu" signal "L6GND")
		(14 "In6.Cu" signal "L7VCC")
		(16 "In7.Cu" signal "L8VCC")
		(18 "In8.Cu" signal "L9GND")
		(20 "In9.Cu" signal "L10")
		(22 "In10.Cu" signal "L11GND")
		(24 "In11.Cu" signal "L12")
		(26 "In12.Cu" signal "L13GND")
		(2 "B.Cu" signal "BOTTOM")
		(9 "F.Adhes" user "F.Adhesive")
		(11 "B.Adhes" user "B.Adhesive")
		(13 "F.Paste" user "Package Geometry/Pastemask Top")
		(15 "B.Paste" user "Package Geometry/Pastemask Bottom")
		(5 "F.SilkS" user "Ref Des/Silkscreen Top")
		(7 "B.SilkS" user "Ref Des/Silkscreen Bottom")
		(1 "F.Mask" user "Board Geometry/Soldermask Top")
		(3 "B.Mask" user "Board Geometry/Soldermask Bottom")
		(17 "Dwgs.User" user "User.Drawings")
		(19 "Cmts.User" user "User.Comments")
		(21 "Eco1.User" user "User.Eco1")
		(23 "Eco2.User" user "User.Eco2")
		(25 "Edge.Cuts" user "Board Geometry/Outline")
		(27 "Margin" user)
		(31 "F.CrtYd" user "Package Geometry/Place Bound Top")
		(29 "B.CrtYd" user "Package Geometry/Place Bound Bottom")
		(35 "F.Fab" user "Ref Des/Assembly Top")
		(33 "B.Fab" user "Ref Des/Assembly Bottom")
	)
	(footprint ""
		(layer "F.Cu")
		(at 414.8836 -94.7166)
		(property "Reference" "R7W18"
			(at -0.8382 -0.67818 0)
			(unlocked yes)
			(layer "F.SilkS")
			(effects
				(font
					(size 0.4064 0.254)
					(thickness 0.1524)
				)
				(justify left)
			)
		)
		(property "Value" ""
			(at 0 0 0)
			(layer "F.Fab")
			(effects
				(font
					(size 1.27 1.27)
				)
			)
		)
		(duplicate_pad_numbers_are_jumpers no)
		(fp_poly
			(pts
				(xy -0.2794 -0.1016) (xy 0.2794 -0.1016) (xy 0.2794 0.9906) (xy -0.2794 0.9906)
			)
			(stroke
				(width 0)
				(type default)
			)
			(fill no)
			(layer "F.CrtYd")
		)
		(fp_line
			(start -0.2794 -0.1016)
			(end -0.2794 0.9906)
			(stroke
				(width 0.1)
				(type default)
			)
			(layer "F.Fab")
		)
		(fp_line
			(start -0.2794 0.9906)
			(end 0.2794 0.9906)
			(stroke
				(width 0.1)
				(type default)
			)
			(layer "F.Fab")
		)
		(fp_line
			(start 0.2794 -0.1016)
			(end -0.2794 -0.1016)
			(stroke
				(width 0.1)
				(type default)
			)
			(layer "F.Fab")
		)
		(fp_line
			(start 0.2794 0.9906)
			(end 0.2794 -0.1016)
			(stroke
				(width 0.1)
				(type default)
			)
			(layer "F.Fab")
		)
		(pad "1" smd rect
			(at 0 0)
			(size 0.508 0.508)
			(layers "F.Cu" "F.Mask" "F.Paste")
			(net "IRQ_SML1_PMBUS_ALERT_N")
		)
		(pad "2" smd rect
			(at 0 0.889)
			(size 0.508 0.508)
			(layers "F.Cu" "F.Mask" "F.Paste")
			(net "IRQ_SML1_PMBUS_ALERT_R1_N")
		)
		(zone
			(layer "F.Cu")
			(hatch none 0.5)
			(connect_pads
				(clearance 0)
			)
			(min_thickness 0.25)
			(keepout
				(tracks allowed)
				(vias not_allowed)
				(pads allowed)
				(copperpour not_allowed)
				(footprints allowed)
			)
			(placement
				(enabled no)
				(sheetname "")
			)
			(fill
				(thermal_gap 0.5)
				(thermal_bridge_width 0.5)
				(island_removal_mode 0)
			)
			(polygon
				(pts
					(xy 414.6296 -94.4626) (xy 415.1376 -94.4626) (xy 415.1376 -94.0816) (xy 414.6296 -94.0816)
				)
			)
		)
		(zone
			(layer "F.Cu")
			(hatch none 0.5)
			(connect_pads
				(clearance 0)
			)
			(min_thickness 0.25)
			(keepout
				(tracks not_allowed)
				(vias allowed)
				(pads allowed)
				(copperpour not_allowed)
				(footprints allowed)
			)
			(placement
				(enabled no)
				(sheetname "")
			)
			(fill
				(thermal_gap 0.5)
				(thermal_bridge_width 0.5)
				(island_removal_mode 0)
			)
			(polygon
				(pts
					(xy 414.6296 -94.0816) (xy 415.1376 -94.0816) (xy 415.1376 -94.4626) (xy 414.6296 -94.4626)
				)
			)
		)
	)
	(footprint ""
		(layer "F.Cu")
		(at 472.7575 -138.43 90)
		(property "Reference" "R9A21"
			(at 0 0 90)
			(layer "F.SilkS")
			(hide yes)
			(effects
				(font
					(size 1.27 1.27)
				)
			)
		)
		(property "Value" ""
			(at 0 0 90)
			(layer "F.Fab")
			(effects
				(font
					(size 1.27 1.27)
				)
			)
		)
		(duplicate_pad_numbers_are_jumpers no)
		(fp_poly
			(pts
				(xy -0.2794 -0.1016) (xy 0.2794 -0.1016) (xy 0.2794 0.9906) (xy -0.2794 0.9906)
			)
			(stroke
				(width 0)
				(type default)
			)
			(fill no)
			(layer "F.CrtYd")
		)
		(fp_line
			(start 0.2794 -0.1016)
			(end -0.2794 -0.1016)
			(stroke
				(width 0.1)
				(type default)
			)
			(layer "F.Fab")
		)
		(fp_line
			(start -0.2794 -0.1016)
			(end -0.2794 0.9906)
			(stroke
				(width 0.1)
				(type default)
			)
			(layer "F.Fab")
		)
		(fp_line
			(start 0.2794 0.9906)
			(end 0.2794 -0.1016)
			(stroke
				(width 0.1)
				(type default)
			)
			(layer "F.Fab")
		)
		(fp_line
			(start -0.2794 0.9906)
			(end 0.2794 0.9906)
			(stroke
				(width 0.1)
				(type default)
			)
			(layer "F.Fab")
		)
		(pad "1" smd rect
			(at 0 0 90)
			(size 0.508 0.508)
			(layers "F.Cu" "F.Mask" "F.Paste")
			(net "P3V3_STBY")
		)
		(pad "2" smd rect
			(at 0 0.889 90)
			(size 0.508 0.508)
			(layers "F.Cu" "F.Mask" "F.Paste")
			(net "FM_PWR_LED_N")
		)
		(zone
			(layer "F.Cu")
			(hatch none 0.5)
			(connect_pads
				(clearance 0)
			)
			(min_thickness 0.25)
			(keepout
				(tracks allowed)
				(vias not_allowed)
				(pads allowed)
				(copperpour not_allowed)
				(footprints allowed)
			)
			(placement
				(enabled no)
				(sheetname "")
			)
			(fill
				(thermal_gap 0.5)
				(thermal_bridge_width 0.5)
				(island_removal_mode 0)
			)
			(polygon
				(pts
					(xy 473.0115 -138.176) (xy 473.0115 -138.684) (xy 473.3925 -138.684) (xy 473.3925 -138.176)
				)
			)
		)
		(zone
			(layer "F.Cu")
			(hatch none 0.5)
			(connect_pads
				(clearance 0)
			)
			(min_thickness 0.25)
			(keepout
				(tracks not_allowed)
				(vias allowed)
				(pads allowed)
				(copperpour not_allowed)
				(footprints allowed)
			)
			(placement
				(enabled no)
				(sheetname "")
			)
			(fill
				(thermal_gap 0.5)
				(thermal_bridge_width 0.5)
				(island_removal_mode 0)
			)
			(polygon
				(pts
					(xy 473.3925 -138.176) (xy 473.3925 -138.684) (xy 473.0115 -138.684) (xy 473.0115 -138.176)
				)
			)
		)
	)
)
